(kicad_pcb
	(version 20260206)
	(generator "pcbnew")
	(generator_version "10.0")
	(general
		(thickness 1.6)
		(legacy_teardrops no)
	)
	(paper "A4")
	(title_block
		(title "Wiwynn_Tioga_Pass_MB.brd")
		(comment 1 "Tioga Pass / footprints 2698-2704 of 4770")
	)
	(layers
		(0 "F.Cu" signal "TOP")
		(4 "In1.Cu" signal "L2GND")
		(6 "In2.Cu" signal "L3")
		(8 "In3.Cu" signal "L4GND")
		(10 "In4.Cu" signal "L5")
		(12 "In5.Cu" signal "L6GND")
		(14 "In6.Cu" signal "L7VCC")
		(16 "In7.Cu" signal "L8VCC")
		(18 "In8.Cu" signal "L9GND")
		(20 "In9.Cu" signal "L10")
		(22 "In10.Cu" signal "L11GND")
		(24 "In11.Cu" signal "L12")
		(26 "In12.Cu" signal "L13GND")
		(2 "B.Cu" signal "BOTTOM")
		(9 "F.Adhes" user "F.Adhesive")
		(11 "B.Adhes" user "B.Adhesive")
		(13 "F.Paste" user "Package Geometry/Pastemask Top")
		(15 "B.Paste" user "Package Geometry/Pastemask Bottom")
		(5 "F.SilkS" user "Ref Des/Silkscreen Top")
		(7 "B.SilkS" user "Ref Des/Silkscreen Bottom")
		(1 "F.Mask" user "Board Geometry/Soldermask Top")
		(3 "B.Mask" user "Board Geometry/Soldermask Bottom")
		(17 "Dwgs.User" user "User.Drawings")
		(19 "Cmts.User" user "User.Comments")
		(21 "Eco1.User" user "User.Eco1")
		(23 "Eco2.User" user "User.Eco2")
		(25 "Edge.Cuts" user "Board Geometry/Outline")
		(27 "Margin" user)
		(31 "F.CrtYd" user "Package Geometry/Place Bound Top")
		(29 "B.CrtYd" user "Package Geometry/Place Bound Bottom")
		(35 "F.Fab" user "Ref Des/Assembly Top")
		(33 "B.Fab" user "Ref Des/Assembly Bottom")
	)
	(footprint ""
		(layer "B.Cu")
		(at 87.158068 -145.0086 -90)
		(property "Reference" "C8L8"
			(at -1.848866 0.752348 270)
			(unlocked yes)
			(layer "B.SilkS")
			(effects
				(font
					(size 1.27 0.9652)
					(thickness 0.1524)
				)
				(justify mirror)
			)
		)
		(property "Value" ""
			(at 0 0 90)
			(layer "B.Fab")
			(effects
				(font
					(size 1.27 1.27)
				)
				(justify mirror)
			)
		)
		(duplicate_pad_numbers_are_jumpers no)
		(fp_rect
			(start 0.500126 1.598422)
			(end -0.500126 -0.201422)
			(stroke
				(width 0)
				(type default)
			)
			(fill no)
			(layer "B.CrtYd")
		)
		(fp_line
			(start -0.500126 1.598422)
			(end 0.500126 1.598422)
			(stroke
				(width 0.1)
				(type default)
			)
			(layer "B.Fab")
		)
		(fp_line
			(start 0.500126 1.598422)
			(end 0.500126 -0.201422)
			(stroke
				(width 0.1)
				(type default)
			)
			(layer "B.Fab")
		)
		(fp_line
			(start -0.500126 -0.201422)
			(end -0.500126 1.598422)
			(stroke
				(width 0.1)
				(type default)
			)
			(layer "B.Fab")
		)
		(fp_line
			(start 0.500126 -0.201422)
			(end -0.500126 -0.201422)
			(stroke
				(width 0.1)
				(type default)
			)
			(layer "B.Fab")
		)
		(pad "1" smd rect
			(at 0 0 180)
			(size 0.889 0.9906)
			(layers "B.Cu" "B.Mask" "B.Paste")
			(net "PVDDQ_KLM")
		)
		(pad "2" smd rect
			(at 0 1.397 180)
			(size 0.889 0.9906)
			(layers "B.Cu" "B.Mask" "B.Paste")
			(net "GND")
		)
		(zone
			(layer "B.Cu")
			(hatch none 0.5)
			(connect_pads
				(clearance 0)
			)
			(min_thickness 0.25)
			(keepout
				(tracks allowed)
				(vias not_allowed)
				(pads allowed)
				(copperpour not_allowed)
				(footprints allowed)
			)
			(placement
				(enabled no)
				(sheetname "")
			)
			(fill
				(thermal_gap 0.5)
				(thermal_bridge_width 0.5)
				(island_removal_mode 0)
			)
			(polygon
				(pts
					(xy 86.205568 -144.5133) (xy 86.713568 -144.5133) (xy 86.713568 -145.5039) (xy 86.205568 -145.5039)
				)
			)
		)
		(zone
			(layer "B.Cu")
			(hatch none 0.5)
			(connect_pads
				(clearance 0)
			)
			(min_thickness 0.25)
			(keepout
				(tracks not_allowed)
				(vias allowed)
				(pads allowed)
				(copperpour not_allowed)
				(footprints allowed)
			)
			(placement
				(enabled no)
				(sheetname "")
			)
			(fill
				(thermal_gap 0.5)
				(thermal_bridge_width 0.5)
				(island_removal_mode 0)
			)
			(polygon
				(pts
					(xy 86.205568 -144.5133) (xy 86.713568 -144.5133) (xy 86.713568 -145.5039) (xy 86.205568 -145.5039)
				)
			)
		)
	)
	(footprint ""
		(layer "B.Cu")
		(at 96.03232 -126.43358 90)
		(property "Reference" "C8M12"
			(at -1.66497 0.408432 0)
			(unlocked yes)
			(layer "B.SilkS")
			(effects
				(font
					(size 0.7874 0.5842)
					(thickness 0.1524)
				)
				(justify mirror)
			)
		)
		(property "Value" ""
			(at 0 0 90)
			(layer "B.Fab")
			(effects
				(font
					(size 1.27 1.27)
				)
				(justify mirror)
			)
		)
		(duplicate_pad_numbers_are_jumpers no)
		(fp_rect
			(start 0.500126 1.598422)
			(end -0.500126 -0.201422)
			(stroke
				(width 0)
				(type default)
			)
			(fill no)
			(layer "B.CrtYd")
		)
		(fp_line
			(start 0.500126 -0.201422)
			(end -0.500126 -0.201422)
			(stroke
				(width 0.1)
				(type default)
			)
			(layer "B.Fab")
		)
		(fp_line
			(start -0.500126 -0.201422)
			(end -0.500126 1.598422)
			(stroke
				(width 0.1)
				(type default)
			)
			(layer "B.Fab")
		)
		(fp_line
			(start 0.500126 1.598422)
			(end 0.500126 -0.201422)
			(stroke
				(width 0.1)
				(type default)
			)
			(layer "B.Fab")
		)
		(fp_line
			(start -0.500126 1.598422)
			(end 0.500126 1.598422)
			(stroke
				(width 0.1)
				(type default)
			)
			(layer "B.Fab")
		)
		(pad "1" smd rect
			(at 0 0)
			(size 0.889 0.9906)
			(layers "B.Cu" "B.Mask" "B.Paste")
			(net "PVTT_KLM")
		)
		(pad "2" smd rect
			(at 0 1.397)
			(size 0.889 0.9906)
			(layers "B.Cu" "B.Mask" "B.Paste")
			(net "GND")
		)
		(zone
			(layer "B.Cu")
			(hatch none 0.5)
			(connect_pads
				(clearance 0)
			)
			(min_thickness 0.25)
			(keepout
				(tracks not_allowed)
				(vias allowed)
				(pads allowed)
				(copperpour not_allowed)
				(footprints allowed)
			)
			(placement
				(enabled no)
				(sheetname "")
			)
			(fill
				(thermal_gap 0.5)
				(thermal_bridge_width 0.5)
				(island_removal_mode 0)
			)
			(polygon
				(pts
					(xy 96.98482 -126.92888) (xy 96.47682 -126.92888) (xy 96.47682 -125.93828) (xy 96.98482 -125.93828)
				)
			)
		)
		(zone
			(layer "B.Cu")
			(hatch none 0.5)
			(connect_pads
				(clearance 0)
			)
			(min_thickness 0.25)
			(keepout
				(tracks allowed)
				(vias not_allowed)
				(pads allowed)
				(copperpour not_allowed)
				(footprints allowed)
			)
			(placement
				(enabled no)
				(sheetname "")
			)
			(fill
				(thermal_gap 0.5)
				(thermal_bridge_width 0.5)
				(island_removal_mode 0)
			)
			(polygon
				(pts
					(xy 96.98482 -126.92888) (xy 96.47682 -126.92888) (xy 96.47682 -125.93828) (xy 96.98482 -125.93828)
				)
			)
		)
	)
	(footprint ""
		(layer "B.Cu")
		(at 496.016534 -38.029896 90)
		(property "Reference" "R9F26"
			(at 0 0 90)
			(layer "B.SilkS")
			(hide yes)
			(effects
				(font
					(size 1.27 1.27)
				)
				(justify mirror)
			)
		)
		(property "Value" ""
			(at 0 0 90)
			(layer "B.Fab")
			(effects
				(font
					(size 1.27 1.27)
				)
				(justify mirror)
			)
		)
		(duplicate_pad_numbers_are_jumpers no)
		(fp_poly
			(pts
				(xy 0.2794 -0.1016) (xy -0.2794 -0.1016) (xy -0.2794 0.9906) (xy 0.2794 0.9906)
			)
			(stroke
				(width 0)
				(type default)
			)
			(fill no)
			(layer "B.CrtYd")
		)
		(fp_line
			(start 0.2794 -0.1016)
			(end 0.2794 0.9906)
			(stroke
				(width 0.1)
				(type default)
			)
			(layer "B.Fab")
		)
		(fp_line
			(start -0.2794 -0.1016)
			(end 0.2794 -0.1016)
			(stroke
				(width 0.1)
				(type default)
			)
			(layer "B.Fab")
		)
		(fp_line
			(start 0.2794 0.9906)
			(end -0.2794 0.9906)
			(stroke
				(width 0.1)
				(type default)
			)
			(layer "B.Fab")
		)
		(fp_line
			(start -0.2794 0.9906)
			(end -0.2794 -0.1016)
			(stroke
				(width 0.1)
				(type default)
			)
			(layer "B.Fab")
		)
		(pad "1" smd rect
			(at 0 0 270)
			(size 0.508 0.508)
			(layers "B.Cu" "B.Mask" "B.Paste")
			(net "SP2_BMC_CM_UART_TX")
		)
		(pad "2" smd rect
			(at 0 0.889 270)
			(size 0.508 0.508)
			(layers "B.Cu" "B.Mask" "B.Paste")
			(net "SPA_MID_DBG_TX")
		)
		(zone
			(layer "B.Cu")
			(hatch none 0.5)
			(connect_pads
				(clearance 0)
			)
			(min_thickness 0.25)
			(keepout
				(tracks allowed)
				(vias not_allowed)
				(pads allowed)
				(copperpour not_allowed)
				(footprints allowed)
			)
			(placement
				(enabled no)
				(sheetname "")
			)
			(fill
				(thermal_gap 0.5)
				(thermal_bridge_width 0.5)
				(island_removal_mode 0)
			)
			(polygon
				(pts
					(xy 496.270534 -38.283896) (xy 496.270534 -37.775896) (xy 496.651534 -37.775896) (xy 496.651534 -38.283896)
				)
			)
		)
		(zone
			(layer "B.Cu")
			(hatch none 0.5)
			(connect_pads
				(clearance 0)
			)
			(min_thickness 0.25)
			(keepout
				(tracks not_allowed)
				(vias allowed)
				(pads allowed)
				(copperpour not_allowed)
				(footprints allowed)
			)
			(placement
				(enabled no)
				(sheetname "")
			)
			(fill
				(thermal_gap 0.5)
				(thermal_bridge_width 0.5)
				(island_removal_mode 0)
			)
			(polygon
				(pts
					(xy 496.651534 -38.283896) (xy 496.651534 -37.775896) (xy 496.270534 -37.775896) (xy 496.270534 -38.283896)
				)
			)
		)
	)
	(footprint ""
		(layer "B.Cu")
		(at 257.8862 -149.7838 -90)
		(property "Reference" "C5G63"
			(at -1.14681 0.76708 0)
			(unlocked yes)
			(layer "B.SilkS")
			(effects
				(font
					(size 0.7874 0.5842)
					(thickness 0.1524)
				)
				(justify mirror)
			)
		)
		(property "Value" ""
			(at 0 0 90)
			(layer "B.Fab")
			(effects
				(font
					(size 1.27 1.27)
				)
				(justify mirror)
			)
		)
		(duplicate_pad_numbers_are_jumpers no)
		(fp_rect
			(start -0.4953 -0.2032)
			(end 0.4953 1.6002)
			(stroke
				(width 0)
				(type default)
			)
			(fill no)
			(layer "B.CrtYd")
		)
		(fp_line
			(start -0.4953 1.6002)
			(end 0.4953 1.6002)
			(stroke
				(width 0.1)
				(type default)
			)
			(layer "B.Fab")
		)
		(fp_line
			(start 0.4953 1.6002)
			(end 0.4953 -0.2032)
			(stroke
				(width 0.1)
				(type default)
			)
			(layer "B.Fab")
		)
		(fp_line
			(start -0.4953 -0.2032)
			(end -0.4953 1.6002)
			(stroke
				(width 0.1)
				(type default)
			)
			(layer "B.Fab")
		)
		(fp_line
			(start 0.4953 -0.2032)
			(end -0.4953 -0.2032)
			(stroke
				(width 0.1)
				(type default)
			)
			(layer "B.Fab")
		)
		(pad "1" smd rect
			(at 0 0 90)
			(size 0.762 0.889)
			(layers "B.Cu" "B.Mask" "B.Paste")
			(net "PVDDQ_DEF")
		)
		(pad "2" smd rect
			(at 0 1.397 90)
			(size 0.762 0.889)
			(layers "B.Cu" "B.Mask" "B.Paste")
			(net "GND")
		)
		(zone
			(layer "B.Cu")
			(hatch none 0.5)
			(connect_pads
				(clearance 0)
			)
			(min_thickness 0.25)
			(keepout
				(tracks not_allowed)
				(vias allowed)
				(pads allowed)
				(copperpour not_allowed)
				(footprints allowed)
			)
			(placement
				(enabled no)
				(sheetname "")
			)
			(fill
				(thermal_gap 0.5)
				(thermal_bridge_width 0.5)
				(island_removal_mode 0)
			)
			(polygon
				(pts
					(xy 257.4417 -150.1648) (xy 256.9337 -150.1648) (xy 256.9337 -149.4028) (xy 257.4417 -149.4028)
				)
			)
		)
	)
	(footprint ""
		(layer "B.Cu")
		(at 448.31 -147.066 180)
		(property "Reference" "C25W98"
			(at 0.8382 -0.67818 180)
			(unlocked yes)
			(layer "B.SilkS")
			(effects
				(font
					(size 0.4064 0.254)
					(thickness 0.1524)
				)
				(justify left mirror)
			)
		)
		(property "Value" ""
			(at 0 0 0)
			(layer "B.Fab")
			(effects
				(font
					(size 1.27 1.27)
				)
				(justify mirror)
			)
		)
		(duplicate_pad_numbers_are_jumpers no)
		(fp_poly
			(pts
				(xy -0.3048 -0.1016) (xy -0.3048 0.9906) (xy 0.3048 0.9906) (xy 0.3048 -0.1016)
			)
			(stroke
				(width 0)
				(type default)
			)
			(fill no)
			(layer "B.CrtYd")
		)
		(fp_line
			(start 0.3048 0.9906)
			(end -0.3048 0.9906)
			(stroke
				(width 0.1)
				(type default)
			)
			(layer "B.Fab")
		)
		(fp_line
			(start 0.3048 -0.1016)
			(end 0.3048 0.9906)
			(stroke
				(width 0.1)
				(type default)
			)
			(layer "B.Fab")
		)
		(fp_line
			(start -0.3048 0.9906)
			(end -0.3048 -0.1016)
			(stroke
				(width 0.1)
				(type default)
			)
			(layer "B.Fab")
		)
		(fp_line
			(start -0.3048 -0.1016)
			(end 0.3048 -0.1016)
			(stroke
				(width 0.1)
				(type default)
			)
			(layer "B.Fab")
		)
		(pad "1" smd rect
			(at 0 0)
			(size 0.508 0.508)
			(layers "B.Cu" "B.Mask" "B.Paste")
			(net "P3V3_STBY")
		)
		(pad "2" smd rect
			(at 0 0.889)
			(size 0.508 0.508)
			(layers "B.Cu" "B.Mask" "B.Paste")
			(net "GND")
		)
		(zone
			(layer "B.Cu")
			(hatch none 0.5)
			(connect_pads
				(clearance 0)
			)
			(min_thickness 0.25)
			(keepout
				(tracks not_allowed)
				(vias allowed)
				(pads allowed)
				(copperpour not_allowed)
				(footprints allowed)
			)
			(placement
				(enabled no)
				(sheetname "")
			)
			(fill
				(thermal_gap 0.5)
				(thermal_bridge_width 0.5)
				(island_removal_mode 0)
			)
			(polygon
				(pts
					(xy 448.056 -147.701) (xy 448.564 -147.701) (xy 448.564 -147.32) (xy 448.056 -147.32)
				)
			)
		)
		(zone
			(layer "B.Cu")
			(hatch none 0.5)
			(connect_pads
				(clearance 0)
			)
			(min_thickness 0.25)
			(keepout
				(tracks allowed)
				(vias not_allowed)
				(pads allowed)
				(copperpour not_allowed)
				(footprints allowed)
			)
			(placement
				(enabled no)
				(sheetname "")
			)
			(fill
				(thermal_gap 0.5)
				(thermal_bridge_width 0.5)
				(island_removal_mode 0)
			)
			(polygon
				(pts
					(xy 448.056 -147.32) (xy 448.564 -147.32) (xy 448.564 -147.701) (xy 448.056 -147.701)
				)
			)
		)
	)
	(footprint ""
		(layer "B.Cu")
		(at 483.0445 -48.514 -90)
		(property "Reference" "R9E1"
			(at 0 0 90)
			(layer "B.SilkS")
			(hide yes)
			(effects
				(font
					(size 1.27 1.27)
				)
				(justify mirror)
			)
		)
		(property "Value" ""
			(at 0 0 90)
			(layer "B.Fab")
			(effects
				(font
					(size 1.27 1.27)
				)
				(justify mirror)
			)
		)
		(duplicate_pad_numbers_are_jumpers no)
		(fp_poly
			(pts
				(xy 0.2794 -0.1016) (xy -0.2794 -0.1016) (xy -0.2794 0.9906) (xy 0.2794 0.9906)
			)
			(stroke
				(width 0)
				(type default)
			)
			(fill no)
			(layer "B.CrtYd")
		)
		(fp_line
			(start -0.2794 0.9906)
			(end -0.2794 -0.1016)
			(stroke
				(width 0.1)
				(type default)
			)
			(layer "B.Fab")
		)
		(fp_line
			(start 0.2794 0.9906)
			(end -0.2794 0.9906)
			(stroke
				(width 0.1)
				(type default)
			)
			(layer "B.Fab")
		)
		(fp_line
			(start -0.2794 -0.1016)
			(end 0.2794 -0.1016)
			(stroke
				(width 0.1)
				(type default)
			)
			(layer "B.Fab")
		)
		(fp_line
			(start 0.2794 -0.1016)
			(end 0.2794 0.9906)
			(stroke
				(width 0.1)
				(type default)
			)
			(layer "B.Fab")
		)
		(pad "1" smd rect
			(at 0 0 90)
			(size 0.508 0.508)
			(layers "B.Cu" "B.Mask" "B.Paste")
			(net "P3V3_STBY")
		)
		(pad "2" smd rect
			(at 0 0.889 90)
			(size 0.508 0.508)
			(layers "B.Cu" "B.Mask" "B.Paste")
			(net "PU_JTAG_SPRV_TDI")
		)
		(zone
			(layer "B.Cu")
			(hatch none 0.5)
			(connect_pads
				(clearance 0)
			)
			(min_thickness 0.25)
			(keepout
				(tracks not_allowed)
				(vias allowed)
				(pads allowed)
				(copperpour not_allowed)
				(footprints allowed)
			)
			(placement
				(enabled no)
				(sheetname "")
			)
			(fill
				(thermal_gap 0.5)
				(thermal_bridge_width 0.5)
				(island_removal_mode 0)
			)
			(polygon
				(pts
					(xy 482.4095 -48.26) (xy 482.4095 -48.768) (xy 482.7905 -48.768) (xy 482.7905 -48.26)
				)
			)
		)
		(zone
			(layer "B.Cu")
			(hatch none 0.5)
			(connect_pads
				(clearance 0)
			)
			(min_thickness 0.25)
			(keepout
				(tracks allowed)
				(vias not_allowed)
				(pads allowed)
				(copperpour not_allowed)
				(footprints allowed)
			)
			(placement
				(enabled no)
				(sheetname "")
			)
			(fill
				(thermal_gap 0.5)
				(thermal_bridge_width 0.5)
				(island_removal_mode 0)
			)
			(polygon
				(pts
					(xy 482.7905 -48.26) (xy 482.7905 -48.768) (xy 482.4095 -48.768) (xy 482.4095 -48.26)
				)
			)
		)
	)
	(footprint ""
		(layer "B.Cu")
		(at 484.691944 -17.934178 -90)
		(property "Reference" "C9G1"
			(at 0 0 90)
			(layer "B.SilkS")
			(hide yes)
			(effects
				(font
					(size 1.27 1.27)
				)
				(justify mirror)
			)
		)
		(property "Value" ""
			(at 0 0 90)
			(layer "B.Fab")
			(effects
				(font
					(size 1.27 1.27)
				)
				(justify mirror)
			)
		)
		(duplicate_pad_numbers_are_jumpers no)
		(fp_poly
			(pts
				(xy -0.3048 -0.1016) (xy -0.3048 0.9906) (xy 0.3048 0.9906) (xy 0.3048 -0.1016)
			)
			(stroke
				(width 0)
				(type default)
			)
			(fill no)
			(layer "B.CrtYd")
		)
		(fp_line
			(start -0.3048 0.9906)
			(end -0.3048 -0.1016)
			(stroke
				(width 0.1)
				(type default)
			)
			(layer "B.Fab")
		)
		(fp_line
			(start 0.3048 0.9906)
			(end -0.3048 0.9906)
			(stroke
				(width 0.1)
				(type default)
			)
			(layer "B.Fab")
		)
		(fp_line
			(start -0.3048 -0.1016)
			(end 0.3048 -0.1016)
			(stroke
				(width 0.1)
				(type default)
			)
			(layer "B.Fab")
		)
		(fp_line
			(start 0.3048 -0.1016)
			(end 0.3048 0.9906)
			(stroke
				(width 0.1)
				(type default)
			)
			(layer "B.Fab")
		)
		(pad "1" smd rect
			(at 0 0 90)
			(size 0.508 0.508)
			(layers "B.Cu" "B.Mask" "B.Paste")
			(net "LED_LAN_2_N")
		)
		(pad "2" smd rect
			(at 0 0.889 90)
			(size 0.508 0.508)
			(layers "B.Cu" "B.Mask" "B.Paste")
			(net "GND")
		)
		(zone
			(layer "B.Cu")
			(hatch none 0.5)
			(connect_pads
				(clearance 0)
			)
			(min_thickness 0.25)
			(keepout
				(tracks not_allowed)
				(vias allowed)
				(pads allowed)
				(copperpour not_allowed)
				(footprints allowed)
			)
			(placement
				(enabled no)
				(sheetname "")
			)
			(fill
				(thermal_gap 0.5)
				(thermal_bridge_width 0.5)
				(island_removal_mode 0)
			)
			(polygon
				(pts
					(xy 484.056944 -17.680178) (xy 484.056944 -18.188178) (xy 484.437944 -18.188178) (xy 484.437944 -17.680178)
				)
			)
		)
		(zone
			(layer "B.Cu")
			(hatch none 0.5)
			(connect_pads
				(clearance 0)
			)
			(min_thickness 0.25)
			(keepout
				(tracks allowed)
				(vias not_allowed)
				(pads allowed)
				(copperpour not_allowed)
				(footprints allowed)
			)
			(placement
				(enabled no)
				(sheetname "")
			)
			(fill
				(thermal_gap 0.5)
				(thermal_bridge_width 0.5)
				(island_removal_mode 0)
			)
			(polygon
				(pts
					(xy 484.437944 -17.680178) (xy 484.437944 -18.188178) (xy 484.056944 -18.188178) (xy 484.056944 -17.680178)
				)
			)
		)
	)
)
